(kicad_pcb
	(version 20260206)
	(generator "pcbnew")
	(generator_version "10.0")
	(general
		(thickness 1.6)
		(legacy_teardrops no)
	)
	(paper "A4")
	(title_block
		(title "01162023_DA0F0TEBIF0_F0T_Expander_BD_F_brd_V02_OCP.brd")
		(comment 1 "Grand Teton / footprints 7353-7359 of 9728")
	)
	(layers
		(0 "F.Cu" signal "TOP")
		(4 "In1.Cu" signal "GND")
		(6 "In2.Cu" signal "VCC")
		(8 "In3.Cu" signal "VCC1")
		(10 "In4.Cu" signal "GND1")
		(12 "In5.Cu" signal "IN1")
		(14 "In6.Cu" signal "GND2")
		(16 "In7.Cu" signal "IN2")
		(18 "In8.Cu" signal "GND3")
		(20 "In9.Cu" signal "IN3")
		(22 "In10.Cu" signal "GND4")
		(24 "In11.Cu" signal "IN4")
		(26 "In12.Cu" signal "GND5")
		(28 "In13.Cu" signal "IN5")
		(30 "In14.Cu" signal "GND6")
		(32 "In15.Cu" signal "IN6")
		(34 "In16.Cu" signal "GND7")
		(2 "B.Cu" signal "BOTTOM")
		(9 "F.Adhes" user "F.Adhesive")
		(11 "B.Adhes" user "B.Adhesive")
		(13 "F.Paste" user "Package Geometry/Pastemask Top")
		(15 "B.Paste" user "Package Geometry/Pastemask Bottom")
		(5 "F.SilkS" user "Ref Des/Silkscreen Top")
		(7 "B.SilkS" user "Ref Des/Silkscreen Bottom")
		(1 "F.Mask" user "Board Geometry/Soldermask Top")
		(3 "B.Mask" user "Board Geometry/Soldermask Bottom")
		(17 "Dwgs.User" user "User.Drawings")
		(19 "Cmts.User" user "User.Comments")
		(21 "Eco1.User" user "User.Eco1")
		(23 "Eco2.User" user "User.Eco2")
		(25 "Edge.Cuts" user "Board Geometry/Outline")
		(27 "Margin" user)
		(31 "F.CrtYd" user "Package Geometry/Place Bound Top")
		(29 "B.CrtYd" user "Package Geometry/Place Bound Bottom")
		(35 "F.Fab" user "Ref Des/Assembly Top")
		(33 "B.Fab" user "Ref Des/Assembly Bottom")
	)
	(footprint ""
		(layer "B.Cu")
		(at 111.082836 -84.812378)
		(property "Reference" "C2669"
			(at 0 0 0)
			(layer "B.SilkS")
			(hide yes)
			(effects
				(font
					(size 1.27 1.27)
				)
				(justify mirror)
			)
		)
		(property "Value" ""
			(at 0 0 0)
			(layer "B.Fab")
			(effects
				(font
					(size 1.27 1.27)
				)
				(justify mirror)
			)
		)
		(duplicate_pad_numbers_are_jumpers no)
		(fp_line
			(start -0.7874 -0.4064)
			(end -0.7874 0.4064)
			(stroke
				(width 0.1524)
				(type default)
			)
			(layer "B.SilkS")
		)
		(fp_line
			(start -0.7874 0.4064)
			(end 0.7874 0.4064)
			(stroke
				(width 0.1524)
				(type default)
			)
			(layer "B.SilkS")
		)
		(fp_line
			(start 0.7874 -0.4064)
			(end -0.7874 -0.4064)
			(stroke
				(width 0.1524)
				(type default)
			)
			(layer "B.SilkS")
		)
		(fp_line
			(start 0.7874 0.4064)
			(end 0.7874 -0.4064)
			(stroke
				(width 0.1524)
				(type default)
			)
			(layer "B.SilkS")
		)
		(fp_line
			(start -0.67945 -0.3048)
			(end -0.67945 0.3048)
			(stroke
				(width 0.1)
				(type default)
			)
			(layer "B.Fab")
		)
		(fp_line
			(start -0.67945 0.3048)
			(end -0.120396 0.3048)
			(stroke
				(width 0.1)
				(type default)
			)
			(layer "B.Fab")
		)
		(fp_line
			(start -0.12065 -0.3048)
			(end -0.67945 -0.3048)
			(stroke
				(width 0.1)
				(type default)
			)
			(layer "B.Fab")
		)
		(fp_line
			(start -0.12065 -0.2794)
			(end -0.12065 -0.3048)
			(stroke
				(width 0.1)
				(type default)
			)
			(layer "B.Fab")
		)
		(fp_line
			(start -0.120396 0.2794)
			(end 0.12065 0.2794)
			(stroke
				(width 0.1)
				(type default)
			)
			(layer "B.Fab")
		)
		(fp_line
			(start -0.120396 0.3048)
			(end -0.120396 0.2794)
			(stroke
				(width 0.1)
				(type default)
			)
			(layer "B.Fab")
		)
		(fp_line
			(start 0.12065 -0.305054)
			(end 0.12065 -0.2794)
			(stroke
				(width 0.1)
				(type default)
			)
			(layer "B.Fab")
		)
		(fp_line
			(start 0.12065 -0.2794)
			(end -0.12065 -0.2794)
			(stroke
				(width 0.1)
				(type default)
			)
			(layer "B.Fab")
		)
		(fp_line
			(start 0.12065 0.2794)
			(end 0.12065 0.3048)
			(stroke
				(width 0.1)
				(type default)
			)
			(layer "B.Fab")
		)
		(fp_line
			(start 0.12065 0.3048)
			(end 0.67945 0.3048)
			(stroke
				(width 0.1)
				(type default)
			)
			(layer "B.Fab")
		)
		(fp_line
			(start 0.67945 -0.305054)
			(end 0.12065 -0.305054)
			(stroke
				(width 0.1)
				(type default)
			)
			(layer "B.Fab")
		)
		(fp_line
			(start 0.67945 0.3048)
			(end 0.67945 -0.305054)
			(stroke
				(width 0.1)
				(type default)
			)
			(layer "B.Fab")
		)
		(pad "1" smd circle
			(at 0.40005 0 180)
			(size 0 0)
			(layers "B.Cu" "B.Mask" "B.Paste")
			(net "P3V3_VDD_9ZXL0851_0_7")
		)
		(pad "2" smd circle
			(at -0.40005 0 180)
			(size 0 0)
			(layers "B.Cu" "B.Mask" "B.Paste")
			(net "GND")
		)
	)
	(footprint ""
		(layer "B.Cu")
		(at 363.093 -229.997)
		(property "Reference" "R3501"
			(at 0 0 0)
			(layer "B.SilkS")
			(hide yes)
			(effects
				(font
					(size 1.27 1.27)
				)
				(justify mirror)
			)
		)
		(property "Value" ""
			(at 0 0 0)
			(layer "B.Fab")
			(effects
				(font
					(size 1.27 1.27)
				)
				(justify mirror)
			)
		)
		(duplicate_pad_numbers_are_jumpers no)
		(fp_line
			(start -0.7874 -0.4064)
			(end -0.7874 0.4064)
			(stroke
				(width 0.1524)
				(type default)
			)
			(layer "B.SilkS")
		)
		(fp_line
			(start -0.7874 0.4064)
			(end 0.7874 0.4064)
			(stroke
				(width 0.1524)
				(type default)
			)
			(layer "B.SilkS")
		)
		(fp_line
			(start 0.7874 -0.4064)
			(end -0.7874 -0.4064)
			(stroke
				(width 0.1524)
				(type default)
			)
			(layer "B.SilkS")
		)
		(fp_line
			(start 0.7874 0.4064)
			(end 0.7874 -0.4064)
			(stroke
				(width 0.1524)
				(type default)
			)
			(layer "B.SilkS")
		)
		(fp_line
			(start -0.67945 -0.3048)
			(end -0.67945 0.3048)
			(stroke
				(width 0.1)
				(type default)
			)
			(layer "B.Fab")
		)
		(fp_line
			(start -0.67945 0.3048)
			(end -0.120396 0.3048)
			(stroke
				(width 0.1)
				(type default)
			)
			(layer "B.Fab")
		)
		(fp_line
			(start -0.12065 -0.3048)
			(end -0.67945 -0.3048)
			(stroke
				(width 0.1)
				(type default)
			)
			(layer "B.Fab")
		)
		(fp_line
			(start -0.12065 -0.2794)
			(end -0.12065 -0.3048)
			(stroke
				(width 0.1)
				(type default)
			)
			(layer "B.Fab")
		)
		(fp_line
			(start -0.120396 0.2794)
			(end 0.12065 0.2794)
			(stroke
				(width 0.1)
				(type default)
			)
			(layer "B.Fab")
		)
		(fp_line
			(start -0.120396 0.3048)
			(end -0.120396 0.2794)
			(stroke
				(width 0.1)
				(type default)
			)
			(layer "B.Fab")
		)
		(fp_line
			(start 0.12065 -0.305054)
			(end 0.12065 -0.2794)
			(stroke
				(width 0.1)
				(type default)
			)
			(layer "B.Fab")
		)
		(fp_line
			(start 0.12065 -0.2794)
			(end -0.12065 -0.2794)
			(stroke
				(width 0.1)
				(type default)
			)
			(layer "B.Fab")
		)
		(fp_line
			(start 0.12065 0.2794)
			(end 0.12065 0.3048)
			(stroke
				(width 0.1)
				(type default)
			)
			(layer "B.Fab")
		)
		(fp_line
			(start 0.12065 0.3048)
			(end 0.67945 0.3048)
			(stroke
				(width 0.1)
				(type default)
			)
			(layer "B.Fab")
		)
		(fp_line
			(start 0.67945 -0.305054)
			(end 0.12065 -0.305054)
			(stroke
				(width 0.1)
				(type default)
			)
			(layer "B.Fab")
		)
		(fp_line
			(start 0.67945 0.3048)
			(end 0.67945 -0.305054)
			(stroke
				(width 0.1)
				(type default)
			)
			(layer "B.Fab")
		)
		(pad "1" smd circle
			(at 0.40005 0 180)
			(size 0 0)
			(layers "B.Cu" "B.Mask" "B.Paste")
			(net "SPI_PEX3_SDIO2_R")
		)
		(pad "2" smd circle
			(at -0.40005 0 180)
			(size 0 0)
			(layers "B.Cu" "B.Mask" "B.Paste")
			(net "SPI_PEX3_SDIO2_R1")
		)
	)
	(footprint ""
		(layer "B.Cu")
		(at 417.450016 -300.174914 180)
		(property "Reference" "C3530"
			(at 0 0 0)
			(layer "B.SilkS")
			(hide yes)
			(effects
				(font
					(size 1.27 1.27)
				)
				(justify mirror)
			)
		)
		(property "Value" ""
			(at 0 0 0)
			(layer "B.Fab")
			(effects
				(font
					(size 1.27 1.27)
				)
				(justify mirror)
			)
		)
		(duplicate_pad_numbers_are_jumpers no)
		(fp_line
			(start 0.299974 0.150114)
			(end 0.299974 -0.150114)
			(stroke
				(width 0.1)
				(type default)
			)
			(layer "B.Fab")
		)
		(fp_line
			(start 0.299974 -0.150114)
			(end -0.299974 -0.150114)
			(stroke
				(width 0.1)
				(type default)
			)
			(layer "B.Fab")
		)
		(fp_line
			(start -0.299974 0.150114)
			(end 0.299974 0.150114)
			(stroke
				(width 0.1)
				(type default)
			)
			(layer "B.Fab")
		)
		(fp_line
			(start -0.299974 -0.150114)
			(end -0.299974 0.150114)
			(stroke
				(width 0.1)
				(type default)
			)
			(layer "B.Fab")
		)
		(pad "1" smd rect
			(at 0.2667 0)
			(size 0.3048 0.381)
			(layers "B.Cu" "B.Mask" "B.Paste")
			(net "P1V8_VDDA_PEX3")
		)
		(pad "2" smd rect
			(at -0.2667 0)
			(size 0.3048 0.381)
			(layers "B.Cu" "B.Mask" "B.Paste")
			(net "GND")
		)
	)
	(footprint ""
		(layer "B.Cu")
		(at 288.52495 -297.79976 -90)
		(property "Reference" "C1624"
			(at 0 0 90)
			(layer "B.SilkS")
			(hide yes)
			(effects
				(font
					(size 1.27 1.27)
				)
				(justify mirror)
			)
		)
		(property "Value" ""
			(at 0 0 90)
			(layer "B.Fab")
			(effects
				(font
					(size 1.27 1.27)
				)
				(justify mirror)
			)
		)
		(duplicate_pad_numbers_are_jumpers no)
		(fp_line
			(start -0.299974 0.150114)
			(end 0.299974 0.150114)
			(stroke
				(width 0.1)
				(type default)
			)
			(layer "B.Fab")
		)
		(fp_line
			(start 0.299974 0.150114)
			(end 0.299974 -0.150114)
			(stroke
				(width 0.1)
				(type default)
			)
			(layer "B.Fab")
		)
		(fp_line
			(start -0.299974 -0.150114)
			(end -0.299974 0.150114)
			(stroke
				(width 0.1)
				(type default)
			)
			(layer "B.Fab")
		)
		(fp_line
			(start 0.299974 -0.150114)
			(end -0.299974 -0.150114)
			(stroke
				(width 0.1)
				(type default)
			)
			(layer "B.Fab")
		)
		(pad "1" smd rect
			(at 0.2667 0 90)
			(size 0.3048 0.381)
			(layers "B.Cu" "B.Mask" "B.Paste")
			(net "P0V8_PEX2")
		)
		(pad "2" smd rect
			(at -0.2667 0 90)
			(size 0.3048 0.381)
			(layers "B.Cu" "B.Mask" "B.Paste")
			(net "GND")
		)
	)
	(footprint ""
		(layer "B.Cu")
		(at 128.321816 -211.588858 180)
		(property "Reference" "U105"
			(at 1.53924 -1.966722 0)
			(unlocked yes)
			(layer "B.SilkS")
			(effects
				(font
					(size 0.7874 0.5842)
					(thickness 0.1524)
				)
				(justify mirror)
			)
		)
		(property "Value" ""
			(at 0 0 0)
			(layer "B.Fab")
			(effects
				(font
					(size 1.27 1.27)
				)
				(justify mirror)
			)
		)
		(duplicate_pad_numbers_are_jumpers no)
		(fp_line
			(start 1.7272 1.1176)
			(end 1.7272 -1.1176)
			(stroke
				(width 0.1524)
				(type default)
			)
			(layer "B.SilkS")
		)
		(fp_line
			(start 0.254 -1.1176)
			(end 1.7272 -1.1176)
			(stroke
				(width 0.1524)
				(type default)
			)
			(layer "B.SilkS")
		)
		(fp_line
			(start 0 -0.7366)
			(end 0.254 -1.1176)
			(stroke
				(width 0.1524)
				(type default)
			)
			(layer "B.SilkS")
		)
		(fp_line
			(start -0.254 -1.1176)
			(end 0 -0.7366)
			(stroke
				(width 0.1524)
				(type default)
			)
			(layer "B.SilkS")
		)
		(fp_line
			(start -1.7272 1.1176)
			(end 1.7272 1.1176)
			(stroke
				(width 0.1524)
				(type default)
			)
			(layer "B.SilkS")
		)
		(fp_line
			(start -1.7272 -1.1176)
			(end -0.254 -1.1176)
			(stroke
				(width 0.1524)
				(type default)
			)
			(layer "B.SilkS")
		)
		(fp_line
			(start -1.7272 -1.1176)
			(end -1.7272 1.1176)
			(stroke
				(width 0.1524)
				(type default)
			)
			(layer "B.SilkS")
		)
		(fp_poly
			(pts
				(xy 1.9558 -0.649986) (xy 2.7178 -0.268986) (xy 2.7178 -1.030986)
			)
			(stroke
				(width 0)
				(type default)
			)
			(fill yes)
			(layer "B.SilkS")
		)
		(fp_line
			(start 1.5748 1.1176)
			(end -1.5748 1.1176)
			(stroke
				(width 0.1)
				(type default)
			)
			(layer "B.Fab")
		)
		(fp_line
			(start 1.5748 -1.1176)
			(end 1.5748 1.1176)
			(stroke
				(width 0.1)
				(type default)
			)
			(layer "B.Fab")
		)
		(fp_line
			(start -1.5748 1.1176)
			(end -1.5748 -1.1176)
			(stroke
				(width 0.1)
				(type default)
			)
			(layer "B.Fab")
		)
		(fp_line
			(start -1.5748 -1.1176)
			(end 1.5748 -1.1176)
			(stroke
				(width 0.1)
				(type default)
			)
			(layer "B.Fab")
		)
		(fp_poly
			(pts
				(xy 1.9558 -0.649986) (xy 2.7178 -0.268986) (xy 2.7178 -1.030986)
			)
			(stroke
				(width 0)
				(type default)
			)
			(fill yes)
			(layer "B.Fab")
		)
		(pad "1" smd rect
			(at 0.999998 -0.649986 90)
			(size 0.3556 1.1176)
			(layers "B.Cu" "B.Mask" "B.Paste")
			(net "UART_PEX0_CLI_R_TX")
		)
		(pad "2" smd rect
			(at 0.999998 0 90)
			(size 0.3556 1.1176)
			(layers "B.Cu" "B.Mask" "B.Paste")
			(net "GND")
		)
		(pad "3" smd rect
			(at 0.999998 0.649986 90)
			(size 0.3556 1.1176)
			(layers "B.Cu" "B.Mask" "B.Paste")
			(net "UART_PEX1_CLI_R_TX")
		)
		(pad "4" smd rect
			(at -0.999998 0.649986 90)
			(size 0.3556 1.1176)
			(layers "B.Cu" "B.Mask" "B.Paste")
			(net "UART_PEX1_CLI_BUF_R_TX")
		)
		(pad "5" smd rect
			(at -0.999998 0 90)
			(size 0.3556 1.1176)
			(layers "B.Cu" "B.Mask" "B.Paste")
			(net "P1V8_PEX")
		)
		(pad "6" smd rect
			(at -0.999998 -0.649986 90)
			(size 0.3556 1.1176)
			(layers "B.Cu" "B.Mask" "B.Paste")
			(net "UART_PEX0_CLI_BUF_R_TX")
		)
	)
	(footprint ""
		(layer "B.Cu")
		(at 357.356664 -321.84594 -90)
		(property "Reference" "R6546"
			(at 0 0 90)
			(layer "B.SilkS")
			(hide yes)
			(effects
				(font
					(size 1.27 1.27)
				)
				(justify mirror)
			)
		)
		(property "Value" ""
			(at 0 0 90)
			(layer "B.Fab")
			(effects
				(font
					(size 1.27 1.27)
				)
				(justify mirror)
			)
		)
		(duplicate_pad_numbers_are_jumpers no)
		(fp_line
			(start -0.7874 0.4064)
			(end 0.7874 0.4064)
			(stroke
				(width 0.1524)
				(type default)
			)
			(layer "B.SilkS")
		)
		(fp_line
			(start 0.7874 0.4064)
			(end 0.7874 -0.4064)
			(stroke
				(width 0.1524)
				(type default)
			)
			(layer "B.SilkS")
		)
		(fp_line
			(start -0.7874 -0.4064)
			(end -0.7874 0.4064)
			(stroke
				(width 0.1524)
				(type default)
			)
			(layer "B.SilkS")
		)
		(fp_line
			(start 0.7874 -0.4064)
			(end -0.7874 -0.4064)
			(stroke
				(width 0.1524)
				(type default)
			)
			(layer "B.SilkS")
		)
		(fp_line
			(start -0.67945 0.3048)
			(end -0.120396 0.3048)
			(stroke
				(width 0.1)
				(type default)
			)
			(layer "B.Fab")
		)
		(fp_line
			(start -0.120396 0.3048)
			(end -0.120396 0.2794)
			(stroke
				(width 0.1)
				(type default)
			)
			(layer "B.Fab")
		)
		(fp_line
			(start 0.12065 0.3048)
			(end 0.67945 0.3048)
			(stroke
				(width 0.1)
				(type default)
			)
			(layer "B.Fab")
		)
		(fp_line
			(start 0.67945 0.3048)
			(end 0.67945 -0.305054)
			(stroke
				(width 0.1)
				(type default)
			)
			(layer "B.Fab")
		)
		(fp_line
			(start -0.120396 0.2794)
			(end 0.12065 0.2794)
			(stroke
				(width 0.1)
				(type default)
			)
			(layer "B.Fab")
		)
		(fp_line
			(start 0.12065 0.2794)
			(end 0.12065 0.3048)
			(stroke
				(width 0.1)
				(type default)
			)
			(layer "B.Fab")
		)
		(fp_line
			(start -0.12065 -0.2794)
			(end -0.12065 -0.3048)
			(stroke
				(width 0.1)
				(type default)
			)
			(layer "B.Fab")
		)
		(fp_line
			(start 0.12065 -0.2794)
			(end -0.12065 -0.2794)
			(stroke
				(width 0.1)
				(type default)
			)
			(layer "B.Fab")
		)
		(fp_line
			(start -0.67945 -0.3048)
			(end -0.67945 0.3048)
			(stroke
				(width 0.1)
				(type default)
			)
			(layer "B.Fab")
		)
		(fp_line
			(start -0.12065 -0.3048)
			(end -0.67945 -0.3048)
			(stroke
				(width 0.1)
				(type default)
			)
			(layer "B.Fab")
		)
		(fp_line
			(start 0.12065 -0.305054)
			(end 0.12065 -0.2794)
			(stroke
				(width 0.1)
				(type default)
			)
			(layer "B.Fab")
		)
		(fp_line
			(start 0.67945 -0.305054)
			(end 0.12065 -0.305054)
			(stroke
				(width 0.1)
				(type default)
			)
			(layer "B.Fab")
		)
		(pad "1" smd circle
			(at 0.40005 0 90)
			(size 0 0)
			(layers "B.Cu" "B.Mask" "B.Paste")
			(net "P0V8_SERDES_VDDA_PEX3")
		)
		(pad "2" smd circle
			(at -0.40005 0 90)
			(size 0 0)
			(layers "B.Cu" "B.Mask" "B.Paste")
			(net "P0V8_SERDES_VDDA_PEX3_C9")
		)
	)
	(footprint ""
		(layer "B.Cu")
		(at 231.86771 -215.104218)
		(property "Reference" "C3606"
			(at 0 0 0)
			(layer "B.SilkS")
			(hide yes)
			(effects
				(font
					(size 1.27 1.27)
				)
				(justify mirror)
			)
		)
		(property "Value" ""
			(at 0 0 0)
			(layer "B.Fab")
			(effects
				(font
					(size 1.27 1.27)
				)
				(justify mirror)
			)
		)
		(duplicate_pad_numbers_are_jumpers no)
		(fp_line
			(start -0.69215 -0.2921)
			(end -0.69215 0.2921)
			(stroke
				(width 0.1524)
				(type default)
			)
			(layer "B.SilkS")
		)
		(fp_line
			(start -0.69215 0.2921)
			(end 0.69215 0.2921)
			(stroke
				(width 0.1524)
				(type default)
			)
			(layer "B.SilkS")
		)
		(fp_line
			(start 0.69215 -0.2921)
			(end -0.69215 -0.2921)
			(stroke
				(width 0.1524)
				(type default)
			)
			(layer "B.SilkS")
		)
		(fp_line
			(start 0.69215 0.2921)
			(end 0.69215 -0.2921)
			(stroke
				(width 0.1524)
				(type default)
			)
			(layer "B.SilkS")
		)
		(fp_line
			(start -0.51435 -0.2794)
			(end -0.51435 0.2794)
			(stroke
				(width 0.1)
				(type default)
			)
			(layer "B.Fab")
		)
		(fp_line
			(start -0.51435 0.2794)
			(end 0.51435 0.2794)
			(stroke
				(width 0.1)
				(type default)
			)
			(layer "B.Fab")
		)
		(fp_line
			(start 0.51435 -0.2794)
			(end -0.51435 -0.2794)
			(stroke
				(width 0.1)
				(type default)
			)
			(layer "B.Fab")
		)
		(fp_line
			(start 0.51435 0.2794)
			(end 0.51435 -0.2794)
			(stroke
				(width 0.1)
				(type default)
			)
			(layer "B.Fab")
		)
		(pad "1" smd circle
			(at 0.40005 0 180)
			(size 0 0)
			(layers "B.Cu" "B.Mask" "B.Paste")
			(net "P1V2_BIC_USB2AV12")
		)
		(pad "2" smd circle
			(at -0.40005 0 180)
			(size 0 0)
			(layers "B.Cu" "B.Mask" "B.Paste")
			(net "GND")
		)
		(zone
			(layer "B.Cu")
			(hatch none 0.5)
			(connect_pads
				(clearance 0)
			)
			(min_thickness 0.25)
			(keepout
				(tracks not_allowed)
				(vias allowed)
				(pads allowed)
				(copperpour not_allowed)
				(footprints allowed)
			)
			(placement
				(enabled no)
				(sheetname "")
			)
			(fill
				(thermal_gap 0.5)
				(thermal_bridge_width 0.5)
				(island_removal_mode 0)
			)
			(polygon
				(pts
					(xy 232.05821 -215.016588) (xy 231.96677 -214.958422) (xy 231.76738 -214.958422) (xy 231.67721 -215.016588)
					(xy 231.67721 -215.191848) (xy 231.76738 -215.250268) (xy 231.96677 -215.250268) (xy 232.05821 -215.192102)
				)
			)
		)
	)
)
